(kicad_pcb
	(version 20260206)
	(generator "pcbnew")
	(generator_version "10.0")
	(general
		(thickness 1.6)
		(legacy_teardrops no)
	)
	(paper "A4")
	(title_block
		(title "03242023_DA0F0TMBIJ0_F0T_Motherboard_J_brd_V01_OCP.brd")
		(comment 1 "Grand Teton / footprints 580-587 of 6105")
	)
	(layers
		(0 "F.Cu" signal "TOP")
		(4 "In1.Cu" signal "GND")
		(6 "In2.Cu" signal "IN1")
		(8 "In3.Cu" signal "GND1")
		(10 "In4.Cu" signal "IN2")
		(12 "In5.Cu" signal "GND2")
		(14 "In6.Cu" signal "IN3")
		(16 "In7.Cu" signal "GND3")
		(18 "In8.Cu" signal "VCC")
		(20 "In9.Cu" signal "VCC1")
		(22 "In10.Cu" signal "GND4")
		(24 "In11.Cu" signal "IN4")
		(26 "In12.Cu" signal "GND5")
		(28 "In13.Cu" signal "IN5")
		(30 "In14.Cu" signal "GND6")
		(32 "In15.Cu" signal "IN6")
		(34 "In16.Cu" signal "GND7")
		(2 "B.Cu" signal "BOTTOM")
		(9 "F.Adhes" user "F.Adhesive")
		(11 "B.Adhes" user "B.Adhesive")
		(13 "F.Paste" user "Package Geometry/Pastemask Top")
		(15 "B.Paste" user "Package Geometry/Pastemask Bottom")
		(5 "F.SilkS" user "Ref Des/Silkscreen Top")
		(7 "B.SilkS" user "Ref Des/Silkscreen Bottom")
		(1 "F.Mask" user "Board Geometry/Soldermask Top")
		(3 "B.Mask" user "Board Geometry/Soldermask Bottom")
		(17 "Dwgs.User" user "User.Drawings")
		(19 "Cmts.User" user "User.Comments")
		(21 "Eco1.User" user "User.Eco1")
		(23 "Eco2.User" user "User.Eco2")
		(25 "Edge.Cuts" user "Board Geometry/Outline")
		(27 "Margin" user)
		(31 "F.CrtYd" user "Package Geometry/Place Bound Top")
		(29 "B.CrtYd" user "Package Geometry/Place Bound Bottom")
		(35 "F.Fab" user "Ref Des/Assembly Top")
		(33 "B.Fab" user "Ref Des/Assembly Bottom")
	)
	(footprint ""
		(layer "F.Cu")
		(at 215.95588 -34.508948 180)
		(property "Reference" "R3592"
			(at 0 0 180)
			(layer "F.SilkS")
			(hide yes)
			(effects
				(font
					(size 1.27 1.27)
				)
			)
		)
		(property "Value" ""
			(at 0 0 180)
			(layer "F.Fab")
			(effects
				(font
					(size 1.27 1.27)
				)
			)
		)
		(duplicate_pad_numbers_are_jumpers no)
		(fp_line
			(start 0.7874 0.4064)
			(end -0.7874 0.4064)
			(stroke
				(width 0.1524)
				(type default)
			)
			(layer "F.SilkS")
		)
		(fp_line
			(start 0.7874 -0.4064)
			(end 0.7874 0.4064)
			(stroke
				(width 0.1524)
				(type default)
			)
			(layer "F.SilkS")
		)
		(fp_line
			(start -0.7874 0.4064)
			(end -0.7874 -0.4064)
			(stroke
				(width 0.1524)
				(type default)
			)
			(layer "F.SilkS")
		)
		(fp_line
			(start -0.7874 -0.4064)
			(end 0.7874 -0.4064)
			(stroke
				(width 0.1524)
				(type default)
			)
			(layer "F.SilkS")
		)
		(fp_line
			(start 0.67945 0.3048)
			(end 0.120396 0.3048)
			(stroke
				(width 0.1)
				(type default)
			)
			(layer "F.Fab")
		)
		(fp_line
			(start 0.67945 -0.3048)
			(end 0.67945 0.3048)
			(stroke
				(width 0.1)
				(type default)
			)
			(layer "F.Fab")
		)
		(fp_line
			(start 0.12065 -0.2794)
			(end 0.12065 -0.3048)
			(stroke
				(width 0.1)
				(type default)
			)
			(layer "F.Fab")
		)
		(fp_line
			(start 0.12065 -0.3048)
			(end 0.67945 -0.3048)
			(stroke
				(width 0.1)
				(type default)
			)
			(layer "F.Fab")
		)
		(fp_line
			(start 0.120396 0.3048)
			(end 0.120396 0.2794)
			(stroke
				(width 0.1)
				(type default)
			)
			(layer "F.Fab")
		)
		(fp_line
			(start 0.120396 0.2794)
			(end -0.12065 0.2794)
			(stroke
				(width 0.1)
				(type default)
			)
			(layer "F.Fab")
		)
		(fp_line
			(start -0.12065 0.3048)
			(end -0.67945 0.3048)
			(stroke
				(width 0.1)
				(type default)
			)
			(layer "F.Fab")
		)
		(fp_line
			(start -0.12065 0.2794)
			(end -0.12065 0.3048)
			(stroke
				(width 0.1)
				(type default)
			)
			(layer "F.Fab")
		)
		(fp_line
			(start -0.12065 -0.2794)
			(end 0.12065 -0.2794)
			(stroke
				(width 0.1)
				(type default)
			)
			(layer "F.Fab")
		)
		(fp_line
			(start -0.12065 -0.305054)
			(end -0.12065 -0.2794)
			(stroke
				(width 0.1)
				(type default)
			)
			(layer "F.Fab")
		)
		(fp_line
			(start -0.67945 0.3048)
			(end -0.67945 -0.305054)
			(stroke
				(width 0.1)
				(type default)
			)
			(layer "F.Fab")
		)
		(fp_line
			(start -0.67945 -0.305054)
			(end -0.12065 -0.305054)
			(stroke
				(width 0.1)
				(type default)
			)
			(layer "F.Fab")
		)
		(pad "1" smd circle
			(at -0.40005 0 180)
			(size 0 0)
			(layers "F.Cu" "F.Mask" "F.Paste")
			(net "SMB_INA230_3V3AUX_SCL")
		)
		(pad "2" smd circle
			(at 0.40005 0 180)
			(size 0 0)
			(layers "F.Cu" "F.Mask" "F.Paste")
			(net "SMB_INA230_5_3V3AUX_SCL_R")
		)
	)
	(footprint ""
		(layer "F.Cu")
		(at 463.215736 -385.742434 90)
		(property "Reference" "PC1849"
			(at 0 0 90)
			(layer "F.SilkS")
			(hide yes)
			(effects
				(font
					(size 1.27 1.27)
				)
			)
		)
		(property "Value" ""
			(at 0 0 90)
			(layer "F.Fab")
			(effects
				(font
					(size 1.27 1.27)
				)
			)
		)
		(duplicate_pad_numbers_are_jumpers no)
		(fp_line
			(start 1.524 -0.762)
			(end 1.524 0.762)
			(stroke
				(width 0.1524)
				(type default)
			)
			(layer "F.SilkS")
		)
		(fp_line
			(start -1.524 -0.762)
			(end 1.524 -0.762)
			(stroke
				(width 0.1524)
				(type default)
			)
			(layer "F.SilkS")
		)
		(fp_line
			(start 1.524 0.762)
			(end -1.524 0.762)
			(stroke
				(width 0.1524)
				(type default)
			)
			(layer "F.SilkS")
		)
		(fp_line
			(start -1.524 0.762)
			(end -1.524 -0.762)
			(stroke
				(width 0.1524)
				(type default)
			)
			(layer "F.SilkS")
		)
		(fp_line
			(start 1.1049 -0.724916)
			(end -1.1049 -0.724916)
			(stroke
				(width 0.1)
				(type default)
			)
			(layer "F.Fab")
		)
		(fp_line
			(start -1.1049 -0.724916)
			(end -1.1049 0.724916)
			(stroke
				(width 0.1)
				(type default)
			)
			(layer "F.Fab")
		)
		(fp_line
			(start 1.1049 0.724916)
			(end 1.1049 -0.724916)
			(stroke
				(width 0.1)
				(type default)
			)
			(layer "F.Fab")
		)
		(fp_line
			(start -1.1049 0.724916)
			(end 1.1049 0.724916)
			(stroke
				(width 0.1)
				(type default)
			)
			(layer "F.Fab")
		)
		(pad "1" smd rect
			(at -0.889 0 270)
			(size 1.016 1.27)
			(layers "F.Cu" "F.Mask" "F.Paste")
			(net "SW_P5V_AUX_FLT")
		)
		(pad "2" smd rect
			(at 0.889 0 270)
			(size 1.016 1.27)
			(layers "F.Cu" "F.Mask" "F.Paste")
			(net "GND")
		)
	)
	(footprint ""
		(layer "F.Cu")
		(at 62.35446 -165.11397)
		(property "Reference" "PL17"
			(at -4.10718 -4.488688 0)
			(unlocked yes)
			(layer "F.SilkS")
			(effects
				(font
					(size 0.7874 0.5842)
					(thickness 0.1524)
				)
				(justify left)
			)
		)
		(property "Value" ""
			(at 0 0 0)
			(layer "F.Fab")
			(effects
				(font
					(size 1.27 1.27)
				)
			)
		)
		(duplicate_pad_numbers_are_jumpers no)
		(fp_line
			(start -3.24993 -3.24993)
			(end 3.24993 -3.24993)
			(stroke
				(width 0.1524)
				(type default)
			)
			(layer "F.SilkS")
		)
		(fp_line
			(start -3.24993 -2.2352)
			(end -3.24993 -3.24993)
			(stroke
				(width 0.1524)
				(type default)
			)
			(layer "F.SilkS")
		)
		(fp_line
			(start -3.24993 3.24993)
			(end -3.24993 2.2352)
			(stroke
				(width 0.1524)
				(type default)
			)
			(layer "F.SilkS")
		)
		(fp_line
			(start 3.24993 -3.24993)
			(end 3.24993 -2.2352)
			(stroke
				(width 0.1524)
				(type default)
			)
			(layer "F.SilkS")
		)
		(fp_line
			(start 3.24993 2.2352)
			(end 3.24993 3.24993)
			(stroke
				(width 0.1524)
				(type default)
			)
			(layer "F.SilkS")
		)
		(fp_line
			(start 3.24993 3.24993)
			(end -3.24993 3.24993)
			(stroke
				(width 0.1524)
				(type default)
			)
			(layer "F.SilkS")
		)
		(fp_line
			(start -3.24993 -3.24993)
			(end 3.24993 -3.24993)
			(stroke
				(width 0.1)
				(type default)
			)
			(layer "F.Fab")
		)
		(fp_line
			(start -3.24993 3.24993)
			(end -3.24993 -3.24993)
			(stroke
				(width 0.1)
				(type default)
			)
			(layer "F.Fab")
		)
		(fp_line
			(start 3.24993 -3.24993)
			(end 3.24993 3.24993)
			(stroke
				(width 0.1)
				(type default)
			)
			(layer "F.Fab")
		)
		(fp_line
			(start 3.24993 3.24993)
			(end -3.24993 3.24993)
			(stroke
				(width 0.1)
				(type default)
			)
			(layer "F.Fab")
		)
		(pad "1" smd rect
			(at -2.29997 0)
			(size 2.0066 4.2164)
			(layers "F.Cu" "F.Mask" "F.Paste")
			(net "SW_PVCCD_HV_CPU1_SW1")
		)
		(pad "2" smd rect
			(at 2.29997 0)
			(size 2.0066 4.2164)
			(layers "F.Cu" "F.Mask" "F.Paste")
			(net "PVCCD_HV_CPU1")
		)
	)
	(footprint ""
		(layer "F.Cu")
		(at 126.396242 -354.844858)
		(property "Reference" "PC1259"
			(at 0 0 0)
			(layer "F.SilkS")
			(hide yes)
			(effects
				(font
					(size 1.27 1.27)
				)
			)
		)
		(property "Value" ""
			(at 0 0 0)
			(layer "F.Fab")
			(effects
				(font
					(size 1.27 1.27)
				)
			)
		)
		(duplicate_pad_numbers_are_jumpers no)
		(fp_line
			(start -1.524 -0.762)
			(end 1.524 -0.762)
			(stroke
				(width 0.1524)
				(type default)
			)
			(layer "F.SilkS")
		)
		(fp_line
			(start -1.524 0.762)
			(end -1.524 -0.762)
			(stroke
				(width 0.1524)
				(type default)
			)
			(layer "F.SilkS")
		)
		(fp_line
			(start 1.524 -0.762)
			(end 1.524 0.762)
			(stroke
				(width 0.1524)
				(type default)
			)
			(layer "F.SilkS")
		)
		(fp_line
			(start 1.524 0.762)
			(end -1.524 0.762)
			(stroke
				(width 0.1524)
				(type default)
			)
			(layer "F.SilkS")
		)
		(fp_line
			(start -1.1049 -0.724916)
			(end -1.1049 0.724916)
			(stroke
				(width 0.1)
				(type default)
			)
			(layer "F.Fab")
		)
		(fp_line
			(start -1.1049 0.724916)
			(end 1.1049 0.724916)
			(stroke
				(width 0.1)
				(type default)
			)
			(layer "F.Fab")
		)
		(fp_line
			(start 1.1049 -0.724916)
			(end -1.1049 -0.724916)
			(stroke
				(width 0.1)
				(type default)
			)
			(layer "F.Fab")
		)
		(fp_line
			(start 1.1049 0.724916)
			(end 1.1049 -0.724916)
			(stroke
				(width 0.1)
				(type default)
			)
			(layer "F.Fab")
		)
		(pad "1" smd rect
			(at -0.889 0 180)
			(size 1.016 1.27)
			(layers "F.Cu" "F.Mask" "F.Paste")
			(net "SW_P12V_PVCCIN_CPU1_FLT")
		)
		(pad "2" smd rect
			(at 0.889 0 180)
			(size 1.016 1.27)
			(layers "F.Cu" "F.Mask" "F.Paste")
			(net "GND")
		)
	)
	(footprint ""
		(layer "F.Cu")
		(at 48.581818 -178.060604 90)
		(property "Reference" "PC430"
			(at 0 0 90)
			(layer "F.SilkS")
			(hide yes)
			(effects
				(font
					(size 1.27 1.27)
				)
			)
		)
		(property "Value" ""
			(at 0 0 90)
			(layer "F.Fab")
			(effects
				(font
					(size 1.27 1.27)
				)
			)
		)
		(duplicate_pad_numbers_are_jumpers no)
		(fp_line
			(start 0.7874 -0.4064)
			(end 0.7874 0.4064)
			(stroke
				(width 0.1524)
				(type default)
			)
			(layer "F.SilkS")
		)
		(fp_line
			(start -0.7874 -0.4064)
			(end 0.7874 -0.4064)
			(stroke
				(width 0.1524)
				(type default)
			)
			(layer "F.SilkS")
		)
		(fp_line
			(start 0.7874 0.4064)
			(end -0.7874 0.4064)
			(stroke
				(width 0.1524)
				(type default)
			)
			(layer "F.SilkS")
		)
		(fp_line
			(start -0.7874 0.4064)
			(end -0.7874 -0.4064)
			(stroke
				(width 0.1524)
				(type default)
			)
			(layer "F.SilkS")
		)
		(fp_line
			(start -0.12065 -0.305054)
			(end -0.12065 -0.2794)
			(stroke
				(width 0.1)
				(type default)
			)
			(layer "F.Fab")
		)
		(fp_line
			(start -0.67945 -0.305054)
			(end -0.12065 -0.305054)
			(stroke
				(width 0.1)
				(type default)
			)
			(layer "F.Fab")
		)
		(fp_line
			(start 0.67945 -0.3048)
			(end 0.67945 0.3048)
			(stroke
				(width 0.1)
				(type default)
			)
			(layer "F.Fab")
		)
		(fp_line
			(start 0.12065 -0.3048)
			(end 0.67945 -0.3048)
			(stroke
				(width 0.1)
				(type default)
			)
			(layer "F.Fab")
		)
		(fp_line
			(start 0.12065 -0.2794)
			(end 0.12065 -0.3048)
			(stroke
				(width 0.1)
				(type default)
			)
			(layer "F.Fab")
		)
		(fp_line
			(start -0.12065 -0.2794)
			(end 0.12065 -0.2794)
			(stroke
				(width 0.1)
				(type default)
			)
			(layer "F.Fab")
		)
		(fp_line
			(start 0.120396 0.2794)
			(end -0.12065 0.2794)
			(stroke
				(width 0.1)
				(type default)
			)
			(layer "F.Fab")
		)
		(fp_line
			(start -0.12065 0.2794)
			(end -0.12065 0.3048)
			(stroke
				(width 0.1)
				(type default)
			)
			(layer "F.Fab")
		)
		(fp_line
			(start 0.67945 0.3048)
			(end 0.120396 0.3048)
			(stroke
				(width 0.1)
				(type default)
			)
			(layer "F.Fab")
		)
		(fp_line
			(start 0.120396 0.3048)
			(end 0.120396 0.2794)
			(stroke
				(width 0.1)
				(type default)
			)
			(layer "F.Fab")
		)
		(fp_line
			(start -0.12065 0.3048)
			(end -0.67945 0.3048)
			(stroke
				(width 0.1)
				(type default)
			)
			(layer "F.Fab")
		)
		(fp_line
			(start -0.67945 0.3048)
			(end -0.67945 -0.305054)
			(stroke
				(width 0.1)
				(type default)
			)
			(layer "F.Fab")
		)
		(pad "1" smd circle
			(at -0.40005 0 90)
			(size 0 0)
			(layers "F.Cu" "F.Mask" "F.Paste")
			(net "SW_P12V_PVCCINFAON_CPU1_FLT")
		)
		(pad "2" smd circle
			(at 0.40005 0 90)
			(size 0 0)
			(layers "F.Cu" "F.Mask" "F.Paste")
			(net "GND")
		)
	)
	(footprint ""
		(layer "F.Cu")
		(at 371.297962 -361.570778 90)
		(property "Reference" "PC1252"
			(at 0 0 90)
			(layer "F.SilkS")
			(hide yes)
			(effects
				(font
					(size 1.27 1.27)
				)
			)
		)
		(property "Value" ""
			(at 0 0 90)
			(layer "F.Fab")
			(effects
				(font
					(size 1.27 1.27)
				)
			)
		)
		(duplicate_pad_numbers_are_jumpers no)
		(fp_line
			(start 0.7874 -0.4064)
			(end 0.7874 0.4064)
			(stroke
				(width 0.1524)
				(type default)
			)
			(layer "F.SilkS")
		)
		(fp_line
			(start -0.7874 -0.4064)
			(end 0.7874 -0.4064)
			(stroke
				(width 0.1524)
				(type default)
			)
			(layer "F.SilkS")
		)
		(fp_line
			(start 0.7874 0.4064)
			(end -0.7874 0.4064)
			(stroke
				(width 0.1524)
				(type default)
			)
			(layer "F.SilkS")
		)
		(fp_line
			(start -0.7874 0.4064)
			(end -0.7874 -0.4064)
			(stroke
				(width 0.1524)
				(type default)
			)
			(layer "F.SilkS")
		)
		(fp_line
			(start -0.12065 -0.305054)
			(end -0.12065 -0.2794)
			(stroke
				(width 0.1)
				(type default)
			)
			(layer "F.Fab")
		)
		(fp_line
			(start -0.67945 -0.305054)
			(end -0.12065 -0.305054)
			(stroke
				(width 0.1)
				(type default)
			)
			(layer "F.Fab")
		)
		(fp_line
			(start 0.67945 -0.3048)
			(end 0.67945 0.3048)
			(stroke
				(width 0.1)
				(type default)
			)
			(layer "F.Fab")
		)
		(fp_line
			(start 0.12065 -0.3048)
			(end 0.67945 -0.3048)
			(stroke
				(width 0.1)
				(type default)
			)
			(layer "F.Fab")
		)
		(fp_line
			(start 0.12065 -0.2794)
			(end 0.12065 -0.3048)
			(stroke
				(width 0.1)
				(type default)
			)
			(layer "F.Fab")
		)
		(fp_line
			(start -0.12065 -0.2794)
			(end 0.12065 -0.2794)
			(stroke
				(width 0.1)
				(type default)
			)
			(layer "F.Fab")
		)
		(fp_line
			(start 0.120396 0.2794)
			(end -0.12065 0.2794)
			(stroke
				(width 0.1)
				(type default)
			)
			(layer "F.Fab")
		)
		(fp_line
			(start -0.12065 0.2794)
			(end -0.12065 0.3048)
			(stroke
				(width 0.1)
				(type default)
			)
			(layer "F.Fab")
		)
		(fp_line
			(start 0.67945 0.3048)
			(end 0.120396 0.3048)
			(stroke
				(width 0.1)
				(type default)
			)
			(layer "F.Fab")
		)
		(fp_line
			(start 0.120396 0.3048)
			(end 0.120396 0.2794)
			(stroke
				(width 0.1)
				(type default)
			)
			(layer "F.Fab")
		)
		(fp_line
			(start -0.12065 0.3048)
			(end -0.67945 0.3048)
			(stroke
				(width 0.1)
				(type default)
			)
			(layer "F.Fab")
		)
		(fp_line
			(start -0.67945 0.3048)
			(end -0.67945 -0.305054)
			(stroke
				(width 0.1)
				(type default)
			)
			(layer "F.Fab")
		)
		(pad "1" smd circle
			(at -0.40005 0 90)
			(size 0 0)
			(layers "F.Cu" "F.Mask" "F.Paste")
			(net "SW_PVPP_HBM_CPU0_BST")
		)
		(pad "2" smd circle
			(at 0.40005 0 90)
			(size 0 0)
			(layers "F.Cu" "F.Mask" "F.Paste")
			(net "SW_PVPP_HBM_CPU0_SW")
		)
	)
	(footprint ""
		(layer "F.Cu")
		(at 350.75876 -352.02114 180)
		(property "Reference" "PJ47"
			(at 2.338324 -1.363472 0)
			(unlocked yes)
			(layer "F.SilkS")
			(effects
				(font
					(size 0.7874 0.5842)
					(thickness 0.1524)
				)
				(justify left)
			)
		)
		(property "Value" ""
			(at 0 0 180)
			(layer "F.Fab")
			(effects
				(font
					(size 1.27 1.27)
				)
			)
		)
		(duplicate_pad_numbers_are_jumpers no)
		(pad "1" smd circle
			(at -0.7493 0 270)
			(size 0 0)
			(layers "F.Cu" "F.Mask" "F.Paste")
			(net "VSENSE_PVCCIN_CPU0_DP")
		)
		(pad "2" smd rect
			(at 0.7493 0 90)
			(size 0.7112 0.8128)
			(layers "F.Cu" "F.Mask" "F.Paste")
			(net "SH_PVCCIN_CPU0")
		)
		(zone
			(layer "F.Cu")
			(hatch none 0.5)
			(connect_pads
				(clearance 0)
			)
			(min_thickness 0.25)
			(keepout
				(tracks allowed)
				(vias not_allowed)
				(pads allowed)
				(copperpour not_allowed)
				(footprints allowed)
			)
			(placement
				(enabled no)
				(sheetname "")
			)
			(fill
				(thermal_gap 0.5)
				(thermal_bridge_width 0.5)
				(island_removal_mode 0)
			)
			(polygon
				(pts
					(xy 349.55226 -351.61474) (xy 351.93986 -351.61474) (xy 351.93986 -352.432366) (xy 349.55226 -352.432366)
				)
			)
		)
	)
	(footprint ""
		(layer "F.Cu")
		(at 119.508016 -245.634256 -90)
		(property "Reference" "C429"
			(at 0 0 270)
			(layer "F.SilkS")
			(hide yes)
			(effects
				(font
					(size 1.27 1.27)
				)
			)
		)
		(property "Value" ""
			(at 0 0 270)
			(layer "F.Fab")
			(effects
				(font
					(size 1.27 1.27)
				)
			)
		)
		(duplicate_pad_numbers_are_jumpers no)
		(fp_line
			(start -0.7874 0.4064)
			(end -0.7874 -0.4064)
			(stroke
				(width 0.1524)
				(type default)
			)
			(layer "F.SilkS")
		)
		(fp_line
			(start 0.7874 0.4064)
			(end -0.7874 0.4064)
			(stroke
				(width 0.1524)
				(type default)
			)
			(layer "F.SilkS")
		)
		(fp_line
			(start -0.7874 -0.4064)
			(end 0.7874 -0.4064)
			(stroke
				(width 0.1524)
				(type default)
			)
			(layer "F.SilkS")
		)
		(fp_line
			(start 0.7874 -0.4064)
			(end 0.7874 0.4064)
			(stroke
				(width 0.1524)
				(type default)
			)
			(layer "F.SilkS")
		)
		(fp_line
			(start -0.67945 0.3048)
			(end -0.67945 -0.305054)
			(stroke
				(width 0.1)
				(type default)
			)
			(layer "F.Fab")
		)
		(fp_line
			(start -0.12065 0.3048)
			(end -0.67945 0.3048)
			(stroke
				(width 0.1)
				(type default)
			)
			(layer "F.Fab")
		)
		(fp_line
			(start 0.120396 0.3048)
			(end 0.120396 0.2794)
			(stroke
				(width 0.1)
				(type default)
			)
			(layer "F.Fab")
		)
		(fp_line
			(start 0.67945 0.3048)
			(end 0.120396 0.3048)
			(stroke
				(width 0.1)
				(type default)
			)
			(layer "F.Fab")
		)
		(fp_line
			(start -0.12065 0.2794)
			(end -0.12065 0.3048)
			(stroke
				(width 0.1)
				(type default)
			)
			(layer "F.Fab")
		)
		(fp_line
			(start 0.120396 0.2794)
			(end -0.12065 0.2794)
			(stroke
				(width 0.1)
				(type default)
			)
			(layer "F.Fab")
		)
		(fp_line
			(start -0.12065 -0.2794)
			(end 0.12065 -0.2794)
			(stroke
				(width 0.1)
				(type default)
			)
			(layer "F.Fab")
		)
		(fp_line
			(start 0.12065 -0.2794)
			(end 0.12065 -0.3048)
			(stroke
				(width 0.1)
				(type default)
			)
			(layer "F.Fab")
		)
		(fp_line
			(start 0.12065 -0.3048)
			(end 0.67945 -0.3048)
			(stroke
				(width 0.1)
				(type default)
			)
			(layer "F.Fab")
		)
		(fp_line
			(start 0.67945 -0.3048)
			(end 0.67945 0.3048)
			(stroke
				(width 0.1)
				(type default)
			)
			(layer "F.Fab")
		)
		(fp_line
			(start -0.67945 -0.305054)
			(end -0.12065 -0.305054)
			(stroke
				(width 0.1)
				(type default)
			)
			(layer "F.Fab")
		)
		(fp_line
			(start -0.12065 -0.305054)
			(end -0.12065 -0.2794)
			(stroke
				(width 0.1)
				(type default)
			)
			(layer "F.Fab")
		)
		(pad "1" smd circle
			(at -0.40005 0 270)
			(size 0 0)
			(layers "F.Cu" "F.Mask" "F.Paste")
			(net "PVCCD_HV_CPU1")
		)
		(pad "2" smd circle
			(at 0.40005 0 270)
			(size 0 0)
			(layers "F.Cu" "F.Mask" "F.Paste")
			(net "GND")
		)
	)
)
